(kicad_pcb
	(version 20240108)
	(generator "pcbnew")
	(generator_version "8.0")
	(general
		(thickness 1.62)
		(legacy_teardrops no)
	)
	(paper "A4")
	(title_block
		(title "Jetson Orin Baseboard")
		(date "2025-03-12")
		(rev "1.3.4")
		(company "Antmicro Ltd")
		(comment 1 "www.antmicro.com")
		(comment 9 "footprints 109-112 of 677")
	)
	(layers
		(0 "F.Cu" signal)
		(1 "In1.Cu" signal)
		(2 "In2.Cu" signal)
		(3 "In3.Cu" signal)
		(4 "In4.Cu" jumper)
		(5 "In5.Cu" signal)
		(6 "In6.Cu" signal)
		(31 "B.Cu" signal)
		(32 "B.Adhes" user "B.Adhesive")
		(33 "F.Adhes" user "F.Adhesive")
		(34 "B.Paste" user)
		(35 "F.Paste" user)
		(36 "B.SilkS" user "B.Silkscreen")
		(37 "F.SilkS" user "F.Silkscreen")
		(38 "B.Mask" user)
		(39 "F.Mask" user)
		(40 "Dwgs.User" user "User.Drawings")
		(41 "Cmts.User" user "User.Comments")
		(42 "Eco1.User" user "User.Eco1")
		(43 "Eco2.User" user "User.Eco2")
		(44 "Edge.Cuts" user)
		(45 "Margin" user)
		(46 "B.CrtYd" user "B.Courtyard")
		(47 "F.CrtYd" user "F.Courtyard")
		(48 "B.Fab" user)
		(49 "F.Fab" user)
	)
	(footprint "antmicro-footprints:C_0402_1005Metric"
		(layer "F.Cu")
		(at 58.18 105.21 90)
		(descr "Capacitor SMD 0402")
		(tags "capacitor SMD 0402")
		(property "Reference" "C44"
			(at -1.01 1.27 90)
			(layer "F.SilkS")
			(effects
				(font
					(size 0.7 0.7)
					(thickness 0.15)
				)
				(justify left bottom)
			)
		)
		(property "Value" "C_100n_0402"
			(at 0 1.4 90)
			(layer "F.Fab")
			(effects
				(font
					(size 0.7 0.7)
					(thickness 0.15)
				)
				(justify left bottom)
			)
		)
		(property "Footprint" "antmicro-footprints:C_0402_1005Metric"
			(at 0 0 90)
			(layer "F.Fab")
			(hide yes)
			(effects
				(font
					(size 1.27 1.27)
					(thickness 0.15)
				)
			)
		)
		(property "Datasheet" "https://www.murata.com/products/productdetail?partno=GRM155R61H104KE14%23"
			(at 0 0 90)
			(layer "F.Fab")
			(hide yes)
			(effects
				(font
					(size 1.27 1.27)
					(thickness 0.15)
				)
			)
		)
		(property "Author" "Antmicro"
			(at 163.39 47.03 0)
			(layer "F.Fab")
			(hide yes)
			(effects
				(font
					(size 1 1)
					(thickness 0.15)
				)
			)
		)
		(property "Dielectric" "X5R"
			(at 163.39 47.03 0)
			(layer "F.Fab")
			(hide yes)
			(effects
				(font
					(size 1 1)
					(thickness 0.15)
				)
			)
		)
		(property "License" "Apache-2.0"
			(at 163.39 47.03 0)
			(layer "F.Fab")
			(hide yes)
			(effects
				(font
					(size 1 1)
					(thickness 0.15)
				)
			)
		)
		(property "MPN" "GRM155R61H104KE14D"
			(at 163.39 47.03 0)
			(layer "F.Fab")
			(hide yes)
			(effects
				(font
					(size 1 1)
					(thickness 0.15)
				)
			)
		)
		(property "Manufacturer" "Murata"
			(at 163.39 47.03 0)
			(layer "F.Fab")
			(hide yes)
			(effects
				(font
					(size 1 1)
					(thickness 0.15)
				)
			)
		)
		(property "Val" "100n"
			(at 163.39 47.03 0)
			(layer "F.Fab")
			(hide yes)
			(effects
				(font
					(size 1 1)
					(thickness 0.15)
				)
			)
		)
		(property "Voltage" "50V"
			(at 163.39 47.03 0)
			(layer "F.Fab")
			(hide yes)
			(effects
				(font
					(size 1 1)
					(thickness 0.15)
				)
			)
		)
		(sheetname "Peripherals")
		(sheetfile "peripherals.kicad_sch")
		(attr smd)
		(fp_rect
			(start -0.925 -0.47)
			(end 0.925 0.47)
			(stroke
				(width 0.05)
				(type default)
			)
			(fill none)
			(layer "F.CrtYd")
		)
		(fp_line
			(start 0.504 -0.25)
			(end 0.504 0.248)
			(stroke
				(width 0.15)
				(type solid)
			)
			(layer "F.Fab")
		)
		(fp_line
			(start -0.494 -0.25)
			(end 0.504 -0.25)
			(stroke
				(width 0.15)
				(type solid)
			)
			(layer "F.Fab")
		)
		(fp_line
			(start 0.504 0.248)
			(end -0.494 0.248)
			(stroke
				(width 0.15)
				(type solid)
			)
			(layer "F.Fab")
		)
		(fp_line
			(start -0.494 0.248)
			(end -0.494 -0.25)
			(stroke
				(width 0.15)
				(type solid)
			)
			(layer "F.Fab")
		)
		(fp_text user "Author: Antmicro"
			(at -0.932 4.17 90)
			(layer "F.Fab")
			(hide yes)
			(effects
				(font
					(size 0.7 0.7)
					(thickness 0.15)
				)
				(justify left bottom)
			)
		)
		(fp_text user "License: Apache-2.0"
			(at -0.932 5.17 90)
			(layer "F.Fab")
			(hide yes)
			(effects
				(font
					(size 0.7 0.7)
					(thickness 0.15)
				)
				(justify left bottom)
			)
		)
		(fp_text user "${REFERENCE}"
			(at -0.932 3.168 90)
			(layer "F.Fab")
			(hide yes)
			(effects
				(font
					(size 0.7 0.7)
					(thickness 0.15)
				)
				(justify left bottom)
			)
		)
		(pad "1" smd roundrect
			(at -0.48 0 90)
			(size 0.59 0.64)
			(layers "F.Cu" "F.Paste" "F.Mask")
			(roundrect_rratio 0.25)
			(net 1 "GND")
			(pintype "passive")
		)
		(pad "2" smd roundrect
			(at 0.48 0 90)
			(size 0.59 0.64)
			(layers "F.Cu" "F.Paste" "F.Mask")
			(roundrect_rratio 0.25)
			(net 112 "+1V8")
			(pintype "passive")
		)
	)
	(footprint "antmicro-footprints:R_0402_1005Metric"
		(layer "F.Cu")
		(at 66.21 99.99)
		(descr "Resistor SMD 0402")
		(tags "resistor SMD 0402")
		(property "Reference" "R269"
			(at -1.7 2.2 0)
			(layer "F.SilkS")
			(effects
				(font
					(size 0.7 0.7)
					(thickness 0.15)
				)
				(justify left bottom)
			)
		)
		(property "Value" "R_10k_0402"
			(at -1.011843 1.772047 0)
			(layer "F.Fab")
			(effects
				(font
					(size 0.7 0.7)
					(thickness 0.15)
				)
				(justify left bottom)
			)
		)
		(property "Footprint" "antmicro-footprints:R_0402_1005Metric"
			(at 0 0 0)
			(layer "F.Fab")
			(hide yes)
			(effects
				(font
					(size 1.27 1.27)
					(thickness 0.15)
				)
			)
		)
		(property "Datasheet" "https://www.bourns.com/docs/product-datasheets/cr.pdf"
			(at 0 0 0)
			(layer "F.Fab")
			(hide yes)
			(effects
				(font
					(size 1.27 1.27)
					(thickness 0.15)
				)
			)
		)
		(property "Author" "Antmicro"
			(at 0 0 0)
			(layer "F.Fab")
			(hide yes)
			(effects
				(font
					(size 1 1)
					(thickness 0.15)
				)
			)
		)
		(property "License" "Apache-2.0"
			(at 0 0 0)
			(layer "F.Fab")
			(hide yes)
			(effects
				(font
					(size 1 1)
					(thickness 0.15)
				)
			)
		)
		(property "MPN" "CR0402-FX-1002GLF"
			(at 0 0 0)
			(layer "F.Fab")
			(hide yes)
			(effects
				(font
					(size 1 1)
					(thickness 0.15)
				)
			)
		)
		(property "Manufacturer" "Bourns"
			(at 0 0 0)
			(layer "F.Fab")
			(hide yes)
			(effects
				(font
					(size 1 1)
					(thickness 0.15)
				)
			)
		)
		(property "Tolerance" "1%"
			(at 0 0 0)
			(layer "F.Fab")
			(hide yes)
			(effects
				(font
					(size 1 1)
					(thickness 0.15)
				)
			)
		)
		(property "Val" "10k"
			(at 0 0 0)
			(layer "F.Fab")
			(hide yes)
			(effects
				(font
					(size 1 1)
					(thickness 0.15)
				)
			)
		)
		(sheetname "Supply")
		(sheetfile "supply.kicad_sch")
		(attr smd)
		(fp_rect
			(start -0.925 -0.47)
			(end 0.925 0.47)
			(stroke
				(width 0.05)
				(type default)
			)
			(fill none)
			(layer "F.CrtYd")
		)
		(fp_rect
			(start -0.5 -0.25)
			(end 0.5 0.25)
			(stroke
				(width 0.15)
				(type solid)
			)
			(fill none)
			(layer "F.Fab")
		)
		(fp_text user "Author: Antmicro"
			(at -0.95 4.169 0)
			(layer "F.Fab")
			(hide yes)
			(effects
				(font
					(size 0.7 0.7)
					(thickness 0.15)
				)
				(justify left bottom)
			)
		)
		(fp_text user "${REFERENCE}"
			(at -0.95 3.168 0)
			(layer "F.Fab")
			(hide yes)
			(effects
				(font
					(size 0.7 0.7)
					(thickness 0.15)
				)
				(justify left bottom)
			)
		)
		(fp_text user "License: Apache-2.0"
			(at -0.95 5.169 0)
			(layer "F.Fab")
			(hide yes)
			(effects
				(font
					(size 0.7 0.7)
					(thickness 0.15)
				)
				(justify left bottom)
			)
		)
		(pad "1" smd roundrect
			(at -0.48 0)
			(size 0.59 0.64)
			(layers "F.Cu" "F.Paste" "F.Mask")
			(roundrect_rratio 0.25)
			(net 1 "GND")
			(pintype "passive")
		)
		(pad "2" smd roundrect
			(at 0.48 0)
			(size 0.59 0.64)
			(layers "F.Cu" "F.Paste" "F.Mask")
			(roundrect_rratio 0.25)
			(net 766 "/Supply/5V_FB")
			(pintype "passive")
		)
	)
	(footprint "antmicro-footprints:R_0402_1005Metric"
		(layer "F.Cu")
		(at 114.4 90.4 180)
		(descr "Resistor SMD 0402")
		(tags "resistor SMD 0402")
		(property "Reference" "R32"
			(at -0.95 0.45 0)
			(layer "F.SilkS")
			(effects
				(font
					(size 0.7 0.7)
					(thickness 0.15)
				)
				(justify right bottom)
			)
		)
		(property "Value" "R_47k_0402"
			(at 0 1.4 0)
			(layer "F.Fab")
			(effects
				(font
					(size 0.7 0.7)
					(thickness 0.15)
				)
				(justify right bottom)
			)
		)
		(property "Footprint" "antmicro-footprints:R_0402_1005Metric"
			(at 0 0 180)
			(layer "F.Fab")
			(hide yes)
			(effects
				(font
					(size 1.27 1.27)
					(thickness 0.15)
				)
			)
		)
		(property "Datasheet" "https://www.bourns.com/docs/product-datasheets/cr.pdf"
			(at 0 0 180)
			(layer "F.Fab")
			(hide yes)
			(effects
				(font
					(size 1.27 1.27)
					(thickness 0.15)
				)
			)
		)
		(property "Author" "Antmicro"
			(at 228.8 180.8 0)
			(layer "F.Fab")
			(hide yes)
			(effects
				(font
					(size 1 1)
					(thickness 0.15)
				)
			)
		)
		(property "License" "Apache-2.0"
			(at 228.8 180.8 0)
			(layer "F.Fab")
			(hide yes)
			(effects
				(font
					(size 1 1)
					(thickness 0.15)
				)
			)
		)
		(property "MPN" "CR0402-FX-4702GLF"
			(at 228.8 180.8 0)
			(layer "F.Fab")
			(hide yes)
			(effects
				(font
					(size 1 1)
					(thickness 0.15)
				)
			)
		)
		(property "Manufacturer" "Bourns"
			(at 228.8 180.8 0)
			(layer "F.Fab")
			(hide yes)
			(effects
				(font
					(size 1 1)
					(thickness 0.15)
				)
			)
		)
		(property "Tolerance" "1%"
			(at 228.8 180.8 0)
			(layer "F.Fab")
			(hide yes)
			(effects
				(font
					(size 1 1)
					(thickness 0.15)
				)
			)
		)
		(property "Val" "47k"
			(at 228.8 180.8 0)
			(layer "F.Fab")
			(hide yes)
			(effects
				(font
					(size 1 1)
					(thickness 0.15)
				)
			)
		)
		(sheetname "M.2")
		(sheetfile "m-2.kicad_sch")
		(attr smd exclude_from_pos_files exclude_from_bom dnp)
		(fp_rect
			(start -0.925 -0.47)
			(end 0.925 0.47)
			(stroke
				(width 0.05)
				(type default)
			)
			(fill none)
			(layer "F.CrtYd")
		)
		(fp_rect
			(start -0.5 -0.25)
			(end 0.5 0.25)
			(stroke
				(width 0.15)
				(type solid)
			)
			(fill none)
			(layer "F.Fab")
		)
		(fp_text user "License: Apache-2.0"
			(at -0.95 5.169 0)
			(layer "F.Fab")
			(hide yes)
			(effects
				(font
					(size 0.7 0.7)
					(thickness 0.15)
				)
				(justify right bottom)
			)
		)
		(fp_text user "${REFERENCE}"
			(at -0.95 3.168 0)
			(layer "F.Fab")
			(hide yes)
			(effects
				(font
					(size 0.7 0.7)
					(thickness 0.15)
				)
				(justify right bottom)
			)
		)
		(fp_text user "Author: Antmicro"
			(at -0.95 4.169 0)
			(layer "F.Fab")
			(hide yes)
			(effects
				(font
					(size 0.7 0.7)
					(thickness 0.15)
				)
				(justify right bottom)
			)
		)
		(pad "1" smd roundrect
			(at -0.48 0 180)
			(size 0.59 0.64)
			(layers "F.Cu" "F.Paste" "F.Mask")
			(roundrect_rratio 0.25)
			(net 183 "/M.2/~{M2_E_UART_WAKE}")
			(pintype "passive")
		)
		(pad "2" smd roundrect
			(at 0.48 0 180)
			(size 0.59 0.64)
			(layers "F.Cu" "F.Paste" "F.Mask")
			(roundrect_rratio 0.25)
			(net 87 "+3V3")
			(pintype "passive")
		)
	)
	(footprint "antmicro-footprints:TSOT23-6"
		(layer "F.Cu")
		(at 67.77 115.5 -90)
		(property "Reference" "U12"
			(at 0.01 -2.54 90)
			(layer "F.SilkS")
			(effects
				(font
					(size 0.7 0.7)
					(thickness 0.15)
				)
				(justify right bottom)
			)
		)
		(property "Value" "AP22615A_TSOT26"
			(at 0 2.6 90)
			(layer "F.Fab")
			(effects
				(font
					(size 0.7 0.7)
					(thickness 0.15)
				)
				(justify right bottom)
			)
		)
		(property "Footprint" "antmicro-footprints:TSOT23-6"
			(at 0 0 -90)
			(layer "F.Fab")
			(hide yes)
			(effects
				(font
					(size 1.27 1.27)
					(thickness 0.15)
				)
			)
		)
		(property "Datasheet" "https://www.mouser.com/datasheet/2/115/DIOD_S_A0008958405_1-2543193.pdf"
			(at 0 0 -90)
			(layer "F.Fab")
			(hide yes)
			(effects
				(font
					(size 1.27 1.27)
					(thickness 0.15)
				)
			)
		)
		(property "Author" "Antmicro"
			(at -47.73 183.27 0)
			(layer "F.Fab")
			(hide yes)
			(effects
				(font
					(size 1 1)
					(thickness 0.15)
				)
			)
		)
		(property "License" "Apache-2.0"
			(at -47.73 183.27 0)
			(layer "F.Fab")
			(hide yes)
			(effects
				(font
					(size 1 1)
					(thickness 0.15)
				)
			)
		)
		(property "MPN" "AP22615AWU-7"
			(at -47.73 183.27 0)
			(layer "F.Fab")
			(hide yes)
			(effects
				(font
					(size 1 1)
					(thickness 0.15)
				)
			)
		)
		(property "Manufacturer" "Diodes Incorporated"
			(at -47.73 183.27 0)
			(layer "F.Fab")
			(hide yes)
			(effects
				(font
					(size 1 1)
					(thickness 0.15)
				)
			)
		)
		(sheetname "USB Debug, DP")
		(sheetfile "usb.kicad_sch")
		(attr smd)
		(fp_line
			(start -1 1.55)
			(end -1 1.4)
			(stroke
				(width 0.15)
				(type solid)
			)
			(layer "F.SilkS")
		)
		(fp_line
			(start 1 1.55)
			(end -1 1.55)
			(stroke
				(width 0.15)
				(type solid)
			)
			(layer "F.SilkS")
		)
		(fp_line
			(start 1 1.55)
			(end 1 1.4)
			(stroke
				(width 0.15)
				(type solid)
			)
			(layer "F.SilkS")
		)
		(fp_line
			(start 1 -1.497)
			(end 1 -1.375)
			(stroke
				(width 0.15)
				(type solid)
			)
			(layer "F.SilkS")
		)
		(fp_line
			(start 1 -1.497)
			(end -1 -1.5)
			(stroke
				(width 0.15)
				(type solid)
			)
			(layer "F.SilkS")
		)
		(fp_line
			(start -1 -1.5)
			(end -1 -1.375)
			(stroke
				(width 0.15)
				(type solid)
			)
			(layer "F.SilkS")
		)
		(fp_circle
			(center -1.44 -1.5)
			(end -1.39 -1.5)
			(stroke
				(width 0.15)
				(type solid)
			)
			(fill solid)
			(layer "F.SilkS")
		)
		(fp_rect
			(start 1.93 -1.7)
			(end -1.93 1.7)
			(stroke
				(width 0.05)
				(type solid)
			)
			(fill none)
			(layer "F.CrtYd")
		)
		(fp_line
			(start -0.45 -1.521)
			(end -0.876 -1.096)
			(stroke
				(width 0.15)
				(type solid)
			)
			(layer "F.Fab")
		)
		(fp_rect
			(start 0.875 1.528)
			(end -0.875 -1.525)
			(stroke
				(width 0.15)
				(type solid)
			)
			(fill none)
			(layer "F.Fab")
		)
		(fp_text user "Author: Antmicro"
			(at -1.93 5 90)
			(layer "F.Fab")
			(hide yes)
			(effects
				(font
					(size 0.7 0.7)
					(thickness 0.15)
				)
				(justify right bottom)
			)
		)
		(fp_text user "License: Apache-2.0"
			(at -1.93 6.199 90)
			(layer "F.Fab")
			(hide yes)
			(effects
				(font
					(size 0.7 0.7)
					(thickness 0.15)
				)
				(justify right bottom)
			)
		)
		(fp_text user "${REFERENCE}"
			(at -1.93 3.8 90)
			(layer "F.Fab")
			(hide yes)
			(effects
				(font
					(size 0.7 0.7)
					(thickness 0.15)
				)
				(justify right bottom)
			)
		)
		(pad "1" smd rect
			(at -1.301 -0.947 180)
			(size 0.7 1.2)
			(layers "F.Cu" "F.Paste" "F.Mask")
			(net 261 "/USB Debug, DP/USBC0_VBUS")
			(pinfunction "OUT")
			(pintype "power_out")
		)
		(pad "2" smd rect
			(at -1.301 0.004 180)
			(size 0.7 1.2)
			(layers "F.Cu" "F.Paste" "F.Mask")
			(net 1 "GND")
			(pinfunction "GND")
			(pintype "power_in")
		)
		(pad "3" smd rect
			(at -1.301 0.954 180)
			(size 0.7 1.2)
			(layers "F.Cu" "F.Paste" "F.Mask")
			(net 505 "USBC0_FLG")
			(pinfunction "FLG")
			(pintype "output")
		)
		(pad "4" smd rect
			(at 1.299 0.954 180)
			(size 0.7 1.2)
			(layers "F.Cu" "F.Paste" "F.Mask")
			(net 673 "Net-(U12-EN)")
			(pinfunction "EN")
			(pintype "input")
		)
		(pad "5" smd rect
			(at 1.299 0.004 180)
			(size 0.7 1.2)
			(layers "F.Cu" "F.Paste" "F.Mask")
			(net 682 "Net-(U12-ISET)")
			(pinfunction "ISET")
			(pintype "passive")
		)
		(pad "6" smd rect
			(at 1.299 -0.947 180)
			(size 0.7 1.2)
			(layers "F.Cu" "F.Paste" "F.Mask")
			(net 99 "+5V")
			(pinfunction "IN")
			(pintype "power_in")
		)
	)
)
